(kicad_pcb
	(version 20260206)
	(generator "pcbnew")
	(generator_version "10.0")
	(general
		(thickness 1.6)
		(legacy_teardrops no)
	)
	(paper "A4")
	(title_block
		(title "04192023_DAF0TMB3IC0_F0TG_MB_C_brd_V02_OCP.brd")
		(comment 1 "Grand Teton / footprints 774-779 of 8354")
	)
	(layers
		(0 "F.Cu" signal "TOP")
		(4 "In1.Cu" signal "GND")
		(6 "In2.Cu" signal "IN1")
		(8 "In3.Cu" signal "GND1")
		(10 "In4.Cu" signal "IN2")
		(12 "In5.Cu" signal "GND2")
		(14 "In6.Cu" signal "IN3")
		(16 "In7.Cu" signal "GND3")
		(18 "In8.Cu" signal "VCC")
		(20 "In9.Cu" signal "VCC1")
		(22 "In10.Cu" signal "GND4")
		(24 "In11.Cu" signal "IN4")
		(26 "In12.Cu" signal "GND5")
		(28 "In13.Cu" signal "IN5")
		(30 "In14.Cu" signal "GND6")
		(32 "In15.Cu" signal "IN6")
		(34 "In16.Cu" signal "GND7")
		(2 "B.Cu" signal "BOTTOM")
		(9 "F.Adhes" user "F.Adhesive")
		(11 "B.Adhes" user "B.Adhesive")
		(13 "F.Paste" user "Package Geometry/Pastemask Top")
		(15 "B.Paste" user "Package Geometry/Pastemask Bottom")
		(5 "F.SilkS" user "Ref Des/Silkscreen Top")
		(7 "B.SilkS" user "Ref Des/Silkscreen Bottom")
		(1 "F.Mask" user "Board Geometry/Soldermask Top")
		(3 "B.Mask" user "Board Geometry/Soldermask Bottom")
		(17 "Dwgs.User" user "User.Drawings")
		(19 "Cmts.User" user "User.Comments")
		(21 "Eco1.User" user "User.Eco1")
		(23 "Eco2.User" user "User.Eco2")
		(25 "Edge.Cuts" user "Board Geometry/Outline")
		(27 "Margin" user)
		(31 "F.CrtYd" user "Package Geometry/Place Bound Top")
		(29 "B.CrtYd" user "Package Geometry/Place Bound Bottom")
		(35 "F.Fab" user "Ref Des/Assembly Top")
		(33 "B.Fab" user "Ref Des/Assembly Bottom")
	)
	(footprint ""
		(layer "F.Cu")
		(at 365.518446 -30.084522 -90)
		(property "Reference" "R819"
			(at 0 0 270)
			(layer "F.SilkS")
			(hide yes)
			(effects
				(font
					(size 1.27 1.27)
				)
			)
		)
		(property "Value" ""
			(at 0 0 270)
			(layer "F.Fab")
			(effects
				(font
					(size 1.27 1.27)
				)
			)
		)
		(duplicate_pad_numbers_are_jumpers no)
		(fp_line
			(start -0.7874 0.4064)
			(end -0.7874 -0.4064)
			(stroke
				(width 0.1524)
				(type default)
			)
			(layer "F.SilkS")
		)
		(fp_line
			(start 0.7874 0.4064)
			(end -0.7874 0.4064)
			(stroke
				(width 0.1524)
				(type default)
			)
			(layer "F.SilkS")
		)
		(fp_line
			(start -0.7874 -0.4064)
			(end 0.7874 -0.4064)
			(stroke
				(width 0.1524)
				(type default)
			)
			(layer "F.SilkS")
		)
		(fp_line
			(start 0.7874 -0.4064)
			(end 0.7874 0.4064)
			(stroke
				(width 0.1524)
				(type default)
			)
			(layer "F.SilkS")
		)
		(fp_line
			(start -0.67945 0.3048)
			(end -0.67945 -0.305054)
			(stroke
				(width 0.1)
				(type default)
			)
			(layer "F.Fab")
		)
		(fp_line
			(start -0.12065 0.3048)
			(end -0.67945 0.3048)
			(stroke
				(width 0.1)
				(type default)
			)
			(layer "F.Fab")
		)
		(fp_line
			(start 0.120396 0.3048)
			(end 0.120396 0.2794)
			(stroke
				(width 0.1)
				(type default)
			)
			(layer "F.Fab")
		)
		(fp_line
			(start 0.67945 0.3048)
			(end 0.120396 0.3048)
			(stroke
				(width 0.1)
				(type default)
			)
			(layer "F.Fab")
		)
		(fp_line
			(start -0.12065 0.2794)
			(end -0.12065 0.3048)
			(stroke
				(width 0.1)
				(type default)
			)
			(layer "F.Fab")
		)
		(fp_line
			(start 0.120396 0.2794)
			(end -0.12065 0.2794)
			(stroke
				(width 0.1)
				(type default)
			)
			(layer "F.Fab")
		)
		(fp_line
			(start -0.12065 -0.2794)
			(end 0.12065 -0.2794)
			(stroke
				(width 0.1)
				(type default)
			)
			(layer "F.Fab")
		)
		(fp_line
			(start 0.12065 -0.2794)
			(end 0.12065 -0.3048)
			(stroke
				(width 0.1)
				(type default)
			)
			(layer "F.Fab")
		)
		(fp_line
			(start 0.12065 -0.3048)
			(end 0.67945 -0.3048)
			(stroke
				(width 0.1)
				(type default)
			)
			(layer "F.Fab")
		)
		(fp_line
			(start 0.67945 -0.3048)
			(end 0.67945 0.3048)
			(stroke
				(width 0.1)
				(type default)
			)
			(layer "F.Fab")
		)
		(fp_line
			(start -0.67945 -0.305054)
			(end -0.12065 -0.305054)
			(stroke
				(width 0.1)
				(type default)
			)
			(layer "F.Fab")
		)
		(fp_line
			(start -0.12065 -0.305054)
			(end -0.12065 -0.2794)
			(stroke
				(width 0.1)
				(type default)
			)
			(layer "F.Fab")
		)
		(pad "1" smd circle
			(at -0.40005 0 270)
			(size 0 0)
			(layers "F.Cu" "F.Mask" "F.Paste")
			(net "UART_CPU0_LVC3_UART0_R_RX")
		)
		(pad "2" smd circle
			(at 0.40005 0 270)
			(size 0 0)
			(layers "F.Cu" "F.Mask" "F.Paste")
			(net "UART_CPU0_LVC3_UART0_RX")
		)
	)
	(footprint ""
		(layer "F.Cu")
		(at 173.171358 -388.753604)
		(property "Reference" "C373"
			(at 0 0 0)
			(layer "F.SilkS")
			(hide yes)
			(effects
				(font
					(size 1.27 1.27)
				)
			)
		)
		(property "Value" ""
			(at 0 0 0)
			(layer "F.Fab")
			(effects
				(font
					(size 1.27 1.27)
				)
			)
		)
		(duplicate_pad_numbers_are_jumpers no)
		(fp_line
			(start -0.7874 -0.4064)
			(end 0.7874 -0.4064)
			(stroke
				(width 0.1524)
				(type default)
			)
			(layer "F.SilkS")
		)
		(fp_line
			(start -0.7874 0.4064)
			(end -0.7874 -0.4064)
			(stroke
				(width 0.1524)
				(type default)
			)
			(layer "F.SilkS")
		)
		(fp_line
			(start 0.7874 -0.4064)
			(end 0.7874 0.4064)
			(stroke
				(width 0.1524)
				(type default)
			)
			(layer "F.SilkS")
		)
		(fp_line
			(start 0.7874 0.4064)
			(end -0.7874 0.4064)
			(stroke
				(width 0.1524)
				(type default)
			)
			(layer "F.SilkS")
		)
		(fp_line
			(start -0.67945 -0.305054)
			(end -0.12065 -0.305054)
			(stroke
				(width 0.1)
				(type default)
			)
			(layer "F.Fab")
		)
		(fp_line
			(start -0.67945 0.3048)
			(end -0.67945 -0.305054)
			(stroke
				(width 0.1)
				(type default)
			)
			(layer "F.Fab")
		)
		(fp_line
			(start -0.12065 -0.305054)
			(end -0.12065 -0.2794)
			(stroke
				(width 0.1)
				(type default)
			)
			(layer "F.Fab")
		)
		(fp_line
			(start -0.12065 -0.2794)
			(end 0.12065 -0.2794)
			(stroke
				(width 0.1)
				(type default)
			)
			(layer "F.Fab")
		)
		(fp_line
			(start -0.12065 0.2794)
			(end -0.12065 0.3048)
			(stroke
				(width 0.1)
				(type default)
			)
			(layer "F.Fab")
		)
		(fp_line
			(start -0.12065 0.3048)
			(end -0.67945 0.3048)
			(stroke
				(width 0.1)
				(type default)
			)
			(layer "F.Fab")
		)
		(fp_line
			(start 0.120396 0.2794)
			(end -0.12065 0.2794)
			(stroke
				(width 0.1)
				(type default)
			)
			(layer "F.Fab")
		)
		(fp_line
			(start 0.120396 0.3048)
			(end 0.120396 0.2794)
			(stroke
				(width 0.1)
				(type default)
			)
			(layer "F.Fab")
		)
		(fp_line
			(start 0.12065 -0.3048)
			(end 0.67945 -0.3048)
			(stroke
				(width 0.1)
				(type default)
			)
			(layer "F.Fab")
		)
		(fp_line
			(start 0.12065 -0.2794)
			(end 0.12065 -0.3048)
			(stroke
				(width 0.1)
				(type default)
			)
			(layer "F.Fab")
		)
		(fp_line
			(start 0.67945 -0.3048)
			(end 0.67945 0.3048)
			(stroke
				(width 0.1)
				(type default)
			)
			(layer "F.Fab")
		)
		(fp_line
			(start 0.67945 0.3048)
			(end 0.120396 0.3048)
			(stroke
				(width 0.1)
				(type default)
			)
			(layer "F.Fab")
		)
		(pad "1" smd circle
			(at -0.40005 0)
			(size 0 0)
			(layers "F.Cu" "F.Mask" "F.Paste")
			(net "P1V8_CPU1_RT_1D")
		)
		(pad "2" smd circle
			(at 0.40005 0)
			(size 0 0)
			(layers "F.Cu" "F.Mask" "F.Paste")
			(net "GND")
		)
	)
	(footprint ""
		(layer "F.Cu")
		(at 325.430896 -378.95403 -90)
		(property "Reference" "C907"
			(at 0 0 270)
			(layer "F.SilkS")
			(hide yes)
			(effects
				(font
					(size 1.27 1.27)
				)
			)
		)
		(property "Value" ""
			(at 0 0 270)
			(layer "F.Fab")
			(effects
				(font
					(size 1.27 1.27)
				)
			)
		)
		(duplicate_pad_numbers_are_jumpers no)
		(fp_line
			(start -0.299974 0.150114)
			(end -0.299974 -0.150114)
			(stroke
				(width 0.1)
				(type default)
			)
			(layer "F.Fab")
		)
		(fp_line
			(start 0.299974 0.150114)
			(end -0.299974 0.150114)
			(stroke
				(width 0.1)
				(type default)
			)
			(layer "F.Fab")
		)
		(fp_line
			(start -0.299974 -0.150114)
			(end 0.299974 -0.150114)
			(stroke
				(width 0.1)
				(type default)
			)
			(layer "F.Fab")
		)
		(fp_line
			(start 0.299974 -0.150114)
			(end 0.299974 0.150114)
			(stroke
				(width 0.1)
				(type default)
			)
			(layer "F.Fab")
		)
		(pad "1" smd rect
			(at -0.2667 0 270)
			(size 0.3048 0.381)
			(layers "F.Cu" "F.Mask" "F.Paste")
			(net "P5E_CPU0_P0_TX_C_DP<13>")
		)
		(pad "2" smd rect
			(at 0.2667 0 270)
			(size 0.3048 0.381)
			(layers "F.Cu" "F.Mask" "F.Paste")
			(net "P5E_CPU0_P0_TX_DP<13>")
		)
	)
	(footprint ""
		(layer "F.Cu")
		(at 142.06982 -389.344154 180)
		(property "Reference" "R1434"
			(at 0 0 180)
			(layer "F.SilkS")
			(hide yes)
			(effects
				(font
					(size 1.27 1.27)
				)
			)
		)
		(property "Value" ""
			(at 0 0 180)
			(layer "F.Fab")
			(effects
				(font
					(size 1.27 1.27)
				)
			)
		)
		(duplicate_pad_numbers_are_jumpers no)
		(fp_line
			(start 0.32512 0.175006)
			(end -0.32512 0.175006)
			(stroke
				(width 0.1)
				(type default)
			)
			(layer "F.Fab")
		)
		(fp_line
			(start 0.32512 -0.175006)
			(end 0.32512 0.175006)
			(stroke
				(width 0.1)
				(type default)
			)
			(layer "F.Fab")
		)
		(fp_line
			(start -0.32512 0.175006)
			(end -0.32512 -0.175006)
			(stroke
				(width 0.1)
				(type default)
			)
			(layer "F.Fab")
		)
		(fp_line
			(start -0.32512 -0.175006)
			(end 0.32512 -0.175006)
			(stroke
				(width 0.1)
				(type default)
			)
			(layer "F.Fab")
		)
		(pad "1" smd rect
			(at -0.2667 0 180)
			(size 0.3048 0.381)
			(layers "F.Cu" "F.Mask" "F.Paste")
			(net "P1V8_CPU1_RT_1D")
		)
		(pad "2" smd rect
			(at 0.2667 0)
			(size 0.3048 0.381)
			(layers "F.Cu" "F.Mask" "F.Paste")
			(net "RXDET_BYP_RT_CPU1_P3")
		)
	)
	(footprint ""
		(layer "F.Cu")
		(at 281.46629 -97.644204 180)
		(property "Reference" "U151"
			(at 3.44678 -3.32486 0)
			(unlocked yes)
			(layer "F.SilkS")
			(effects
				(font
					(size 0.7874 0.5842)
					(thickness 0.1524)
				)
				(justify left)
			)
		)
		(property "Value" ""
			(at 0 0 180)
			(layer "F.Fab")
			(effects
				(font
					(size 1.27 1.27)
				)
			)
		)
		(duplicate_pad_numbers_are_jumpers no)
		(fp_line
			(start 1.868932 2.549906)
			(end 1.868932 -2.549906)
			(stroke
				(width 0.1524)
				(type default)
			)
			(layer "F.SilkS")
		)
		(fp_line
			(start 1.868932 -2.549906)
			(end 1.025906 -2.549906)
			(stroke
				(width 0.1524)
				(type default)
			)
			(layer "F.SilkS")
		)
		(fp_line
			(start 1.025906 -2.549906)
			(end 0 -1.524)
			(stroke
				(width 0.1524)
				(type default)
			)
			(layer "F.SilkS")
		)
		(fp_line
			(start 0 -1.524)
			(end -1.025906 -2.549906)
			(stroke
				(width 0.1524)
				(type default)
			)
			(layer "F.SilkS")
		)
		(fp_line
			(start -1.025906 -2.549906)
			(end -1.868932 -2.549906)
			(stroke
				(width 0.1524)
				(type default)
			)
			(layer "F.SilkS")
		)
		(fp_line
			(start -1.868932 2.549906)
			(end 1.868932 2.549906)
			(stroke
				(width 0.1524)
				(type default)
			)
			(layer "F.SilkS")
		)
		(fp_line
			(start -1.868932 -2.549906)
			(end -1.868932 2.549906)
			(stroke
				(width 0.1524)
				(type default)
			)
			(layer "F.SilkS")
		)
		(fp_poly
			(pts
				(xy -3.593338 -2.533142) (xy -4.729226 -2.533142) (xy -4.27482 -3.4417)
			)
			(stroke
				(width 0)
				(type default)
			)
			(fill yes)
			(layer "F.SilkS")
		)
		(fp_line
			(start 2.249932 2.549906)
			(end 2.249932 -2.549906)
			(stroke
				(width 0.1)
				(type default)
			)
			(layer "F.Fab")
		)
		(fp_line
			(start 2.249932 -2.549906)
			(end -2.249932 -2.549906)
			(stroke
				(width 0.1)
				(type default)
			)
			(layer "F.Fab")
		)
		(fp_line
			(start -2.249932 2.549906)
			(end 2.249932 2.549906)
			(stroke
				(width 0.1)
				(type default)
			)
			(layer "F.Fab")
		)
		(fp_line
			(start -2.249932 -2.549906)
			(end -2.249932 2.549906)
			(stroke
				(width 0.1)
				(type default)
			)
			(layer "F.Fab")
		)
		(fp_poly
			(pts
				(xy -4.7752 -1.787398) (xy -4.7752 -2.803398) (xy -3.7592 -2.295398)
			)
			(stroke
				(width 0)
				(type default)
			)
			(fill yes)
			(layer "F.Fab")
		)
		(pad "1" smd rect
			(at -2.800096 -2.275078 90)
			(size 0.3556 1.6002)
			(layers "F.Cu" "F.Mask" "F.Paste")
			(net "PVDD18_S5_P0")
		)
		(pad "2" smd rect
			(at -2.800096 -1.625092 90)
			(size 0.3556 1.6002)
			(layers "F.Cu" "F.Mask" "F.Paste")
			(net "PVDD18_S5_P0")
		)
		(pad "3" smd rect
			(at -2.800096 -0.975106 90)
			(size 0.3556 1.6002)
			(layers "F.Cu" "F.Mask" "F.Paste")
			(net "JTAG_TCK")
		)
		(pad "4" smd rect
			(at -2.800096 -0.32512 90)
			(size 0.3556 1.6002)
			(layers "F.Cu" "F.Mask" "F.Paste")
			(net "JTAG_TMS")
		)
		(pad "5" smd rect
			(at -2.800096 0.32512 90)
			(size 0.3556 1.6002)
			(layers "F.Cu" "F.Mask" "F.Paste")
			(net "JTAG_TRST_N")
		)
		(pad "6" smd rect
			(at -2.800096 0.975106 90)
			(size 0.3556 1.6002)
			(layers "F.Cu" "F.Mask" "F.Paste")
			(net "JTAG_DBREQ_N")
		)
		(pad "7" smd rect
			(at -2.800096 1.625092 90)
			(size 0.3556 1.6002)
			(layers "F.Cu" "F.Mask" "F.Paste")
			(net "PVDD18_S5_P0")
		)
		(pad "8" smd rect
			(at -2.800096 2.275078 90)
			(size 0.3556 1.6002)
			(layers "F.Cu" "F.Mask" "F.Paste")
			(net "PVDD18_S5_P0")
		)
		(pad "9" smd rect
			(at 2.800096 2.275078 90)
			(size 0.3556 1.6002)
			(layers "F.Cu" "F.Mask" "F.Paste")
			(net "CPU1_JTAG_BUF_OE")
		)
		(pad "10" smd rect
			(at 2.800096 1.625092 90)
			(size 0.3556 1.6002)
			(layers "F.Cu" "F.Mask" "F.Paste")
			(net "GND")
		)
		(pad "11" smd rect
			(at 2.800096 0.975106 90)
			(size 0.3556 1.6002)
			(layers "F.Cu" "F.Mask" "F.Paste")
			(net "JTAG_P1_R_DBREQ_N")
		)
		(pad "12" smd rect
			(at 2.800096 0.32512 90)
			(size 0.3556 1.6002)
			(layers "F.Cu" "F.Mask" "F.Paste")
			(net "JTAG_P1_R_TRST_N")
		)
		(pad "13" smd rect
			(at 2.800096 -0.32512 90)
			(size 0.3556 1.6002)
			(layers "F.Cu" "F.Mask" "F.Paste")
			(net "JTAG_P1_R_TMS")
		)
		(pad "14" smd rect
			(at 2.800096 -0.975106 90)
			(size 0.3556 1.6002)
			(layers "F.Cu" "F.Mask" "F.Paste")
			(net "JTAG_P1_R_TCK")
		)
		(pad "15" smd rect
			(at 2.800096 -1.625092 90)
			(size 0.3556 1.6002)
			(layers "F.Cu" "F.Mask" "F.Paste")
			(net "PVDD18_S5_P1")
		)
		(pad "16" smd rect
			(at 2.800096 -2.275078 90)
			(size 0.3556 1.6002)
			(layers "F.Cu" "F.Mask" "F.Paste")
			(net "PVDD18_S5_P0")
		)
	)
	(footprint ""
		(layer "F.Cu")
		(at 357.93426 -327.60031 180)
		(property "Reference" "PR51"
			(at 0 0 180)
			(layer "F.SilkS")
			(hide yes)
			(effects
				(font
					(size 1.27 1.27)
				)
			)
		)
		(property "Value" ""
			(at 0 0 180)
			(layer "F.Fab")
			(effects
				(font
					(size 1.27 1.27)
				)
			)
		)
		(duplicate_pad_numbers_are_jumpers no)
		(fp_line
			(start 0.7874 0.4064)
			(end -0.7874 0.4064)
			(stroke
				(width 0.1524)
				(type default)
			)
			(layer "F.SilkS")
		)
		(fp_line
			(start 0.7874 -0.4064)
			(end 0.7874 0.4064)
			(stroke
				(width 0.1524)
				(type default)
			)
			(layer "F.SilkS")
		)
		(fp_line
			(start -0.7874 0.4064)
			(end -0.7874 -0.4064)
			(stroke
				(width 0.1524)
				(type default)
			)
			(layer "F.SilkS")
		)
		(fp_line
			(start -0.7874 -0.4064)
			(end 0.7874 -0.4064)
			(stroke
				(width 0.1524)
				(type default)
			)
			(layer "F.SilkS")
		)
		(fp_line
			(start 0.67945 0.3048)
			(end 0.120396 0.3048)
			(stroke
				(width 0.1)
				(type default)
			)
			(layer "F.Fab")
		)
		(fp_line
			(start 0.67945 -0.3048)
			(end 0.67945 0.3048)
			(stroke
				(width 0.1)
				(type default)
			)
			(layer "F.Fab")
		)
		(fp_line
			(start 0.12065 -0.2794)
			(end 0.12065 -0.3048)
			(stroke
				(width 0.1)
				(type default)
			)
			(layer "F.Fab")
		)
		(fp_line
			(start 0.12065 -0.3048)
			(end 0.67945 -0.3048)
			(stroke
				(width 0.1)
				(type default)
			)
			(layer "F.Fab")
		)
		(fp_line
			(start 0.120396 0.3048)
			(end 0.120396 0.2794)
			(stroke
				(width 0.1)
				(type default)
			)
			(layer "F.Fab")
		)
		(fp_line
			(start 0.120396 0.2794)
			(end -0.12065 0.2794)
			(stroke
				(width 0.1)
				(type default)
			)
			(layer "F.Fab")
		)
		(fp_line
			(start -0.12065 0.3048)
			(end -0.67945 0.3048)
			(stroke
				(width 0.1)
				(type default)
			)
			(layer "F.Fab")
		)
		(fp_line
			(start -0.12065 0.2794)
			(end -0.12065 0.3048)
			(stroke
				(width 0.1)
				(type default)
			)
			(layer "F.Fab")
		)
		(fp_line
			(start -0.12065 -0.2794)
			(end 0.12065 -0.2794)
			(stroke
				(width 0.1)
				(type default)
			)
			(layer "F.Fab")
		)
		(fp_line
			(start -0.12065 -0.305054)
			(end -0.12065 -0.2794)
			(stroke
				(width 0.1)
				(type default)
			)
			(layer "F.Fab")
		)
		(fp_line
			(start -0.67945 0.3048)
			(end -0.67945 -0.305054)
			(stroke
				(width 0.1)
				(type default)
			)
			(layer "F.Fab")
		)
		(fp_line
			(start -0.67945 -0.305054)
			(end -0.12065 -0.305054)
			(stroke
				(width 0.1)
				(type default)
			)
			(layer "F.Fab")
		)
		(pad "1" smd circle
			(at -0.40005 0 180)
			(size 0 0)
			(layers "F.Cu" "F.Mask" "F.Paste")
			(net "VSENSE_PVDDCR_CPU1_P0_DP")
		)
		(pad "2" smd circle
			(at 0.40005 0 180)
			(size 0 0)
			(layers "F.Cu" "F.Mask" "F.Paste")
			(net "PVDDCR_CPU1_P0")
		)
	)
)
